(kicad_pcb
	(version 20260206)
	(generator "pcbnew")
	(generator_version "10.0")
	(general
		(thickness 1.6)
		(legacy_teardrops no)
	)
	(paper "A4")
	(title_block
		(title "Bryce Canyon_F.DPB_16315-1-OCP.brd")
		(comment 1 "Bryce Canyon / footprints 1491-1494 of 2223")
	)
	(layers
		(0 "F.Cu" signal "TOP")
		(4 "In1.Cu" signal "L2GND")
		(6 "In2.Cu" signal "L3")
		(8 "In3.Cu" signal "L4GND")
		(10 "In4.Cu" signal "L5")
		(12 "In5.Cu" signal "L6VCC")
		(14 "In6.Cu" signal "L7VCC")
		(16 "In7.Cu" signal "L8")
		(18 "In8.Cu" signal "L9GND")
		(20 "In9.Cu" signal "L10")
		(22 "In10.Cu" signal "L11GND")
		(2 "B.Cu" signal "BOTTOM")
		(9 "F.Adhes" user "F.Adhesive")
		(11 "B.Adhes" user "B.Adhesive")
		(13 "F.Paste" user "Package Geometry/Pastemask Top")
		(15 "B.Paste" user "Package Geometry/Pastemask Bottom")
		(5 "F.SilkS" user "Ref Des/Silkscreen Top")
		(7 "B.SilkS" user "Ref Des/Silkscreen Bottom")
		(1 "F.Mask" user "Board Geometry/Soldermask Top")
		(3 "B.Mask" user "Board Geometry/Soldermask Bottom")
		(17 "Dwgs.User" user "User.Drawings")
		(19 "Cmts.User" user "User.Comments")
		(21 "Eco1.User" user "User.Eco1")
		(23 "Eco2.User" user "User.Eco2")
		(25 "Edge.Cuts" user "Board Geometry/Outline")
		(27 "Margin" user)
		(31 "F.CrtYd" user "Package Geometry/Place Bound Top")
		(29 "B.CrtYd" user "Package Geometry/Place Bound Bottom")
		(35 "F.Fab" user "Ref Des/Assembly Top")
		(33 "B.Fab" user "Ref Des/Assembly Bottom")
	)
	(footprint ""
		(layer "F.Cu")
		(at 185.950098 -287.910016 -90)
		(property "Reference" "HDDSAS5"
			(at 0 0 270)
			(layer "F.SilkS")
			(hide yes)
			(effects
				(font
					(size 1.27 1.27)
				)
			)
		)
		(property "Value" "SKT-SAS15P-14P-45-GP"
			(at -20.7645 -8.9789 270)
			(unlocked yes)
			(layer "F.Fab")
			(hide yes)
			(effects
				(font
					(size 1.016 1.016)
					(thickness 0.1524)
				)
			)
		)
		(property "Device Type" "10120818-001C-TRLF"
			(at -20.7645 -10.5029 270)
			(unlocked yes)
			(layer "F.Fab")
			(hide yes)
			(effects
				(font
					(size 1.016 1.016)
					(thickness 0.1524)
				)
			)
		)
		(duplicate_pad_numbers_are_jumpers no)
		(fp_line
			(start 1.651 4.2926)
			(end 1.651 3.0099)
			(stroke
				(width 0.1524)
				(type default)
			)
			(layer "F.SilkS")
		)
		(fp_line
			(start 8.509 4.2926)
			(end 1.651 4.2926)
			(stroke
				(width 0.1524)
				(type default)
			)
			(layer "F.SilkS")
		)
		(fp_line
			(start -23.4188 3.0099)
			(end -23.4188 -3.2512)
			(stroke
				(width 0.1524)
				(type default)
			)
			(layer "F.SilkS")
		)
		(fp_line
			(start 1.651 3.0099)
			(end -23.4188 3.0099)
			(stroke
				(width 0.1524)
				(type default)
			)
			(layer "F.SilkS")
		)
		(fp_line
			(start 8.509 3.0099)
			(end 8.509 4.2926)
			(stroke
				(width 0.1524)
				(type default)
			)
			(layer "F.SilkS")
		)
		(fp_line
			(start 23.4188 3.0099)
			(end 8.509 3.0099)
			(stroke
				(width 0.1524)
				(type default)
			)
			(layer "F.SilkS")
		)
		(fp_line
			(start -23.4188 -3.2512)
			(end 23.4188 -3.2512)
			(stroke
				(width 0.1524)
				(type default)
			)
			(layer "F.SilkS")
		)
		(fp_line
			(start 23.4188 -3.2512)
			(end 23.4188 3.0099)
			(stroke
				(width 0.1524)
				(type default)
			)
			(layer "F.SilkS")
		)
		(fp_line
			(start 15.5067 -3.3401)
			(end 16.2687 -3.3401)
			(stroke
				(width 0.3302)
				(type default)
			)
			(layer "F.SilkS")
		)
		(fp_poly
			(pts
				(xy 15.868904 -3.230372) (xy 16.503904 -3.865372) (xy 15.233904 -3.865372)
			)
			(stroke
				(width 0)
				(type default)
			)
			(fill yes)
			(layer "F.SilkS")
		)
		(fp_poly
			(pts
				(xy -22.8727 -2.7559) (xy 22.8727 -2.7559) (xy 22.8727 2.7559) (xy 8.255 2.7559) (xy 8.255 3.5179)
				(xy 1.905 3.5179) (xy 1.905 2.7559) (xy -22.8727 2.7559)
			)
			(stroke
				(width 0)
				(type default)
			)
			(fill no)
			(layer "F.CrtYd")
		)
		(fp_poly
			(pts
				(xy 1.397 4.5466) (xy 1.397 3.2639) (xy -23.6728 3.2639) (xy -23.6728 -3.5052) (xy 23.6728 -3.5052)
				(xy 23.6728 -0.00635) (xy 22.8727 -0.00635) (xy 22.8727 -2.7559) (xy -22.8727 -2.7559) (xy -22.8727 2.7559)
				(xy 1.905 2.7559) (xy 1.905 3.5179) (xy 8.255 3.5179) (xy 8.255 2.7559) (xy 22.8727 2.7559) (xy 22.8727 0.00635)
				(xy 23.6728 0.00635) (xy 23.6728 3.2639) (xy 8.763 3.2639) (xy 8.763 4.5466)
			)
			(stroke
				(width 0)
				(type default)
			)
			(fill no)
			(layer "F.CrtYd")
		)
		(fp_poly
			(pts
				(xy 1.397 4.5466) (xy 1.397 3.2639) (xy -23.6728 3.2639) (xy -23.6728 -3.5052) (xy 23.6728 -3.5052)
				(xy 23.6728 3.2639) (xy 8.763 3.2639) (xy 8.763 4.5466)
			)
			(stroke
				(width 0)
				(type default)
			)
			(fill no)
			(layer "F.Fab")
		)
		(pad "" np_thru_hole circle
			(at -18.874994 0 270)
			(size 0.254 0.254)
			(drill 1.3462)
			(layers "*.Cu" "*.Mask")
			(clearance 0.9017)
			(thermal_gap 0.9017)
		)
		(pad "" np_thru_hole circle
			(at 18.874994 0 270)
			(size 0.254 0.254)
			(drill 0.9398)
			(layers "*.Cu" "*.Mask")
			(clearance 0.6985)
			(thermal_gap 0.6985)
		)
		(pad "G1" smd rect
			(at 21.874988 0 270)
			(size 2.5908 2.5908)
			(layers "F.Cu" "F.Mask" "F.Paste")
			(net "GND")
		)
		(pad "G2" smd rect
			(at -21.874988 0 270)
			(size 2.5908 2.5908)
			(layers "F.Cu" "F.Mask" "F.Paste")
			(net "GND")
		)
		(pad "P1" smd rect
			(at 1.905 -1.82499 270)
			(size 0.6096 2.3622)
			(layers "F.Cu" "F.Mask" "F.Paste")
			(net "Net_2016")
		)
		(pad "P2" smd rect
			(at 0.635 -1.82499 270)
			(size 0.6096 2.3622)
			(layers "F.Cu" "F.Mask" "F.Paste")
			(net "Net_2017")
		)
		(pad "P3" smd rect
			(at -0.635 -1.82499 270)
			(size 0.6096 2.3622)
			(layers "F.Cu" "F.Mask" "F.Paste")
			(net "Net_2018")
		)
		(pad "P4" smd rect
			(at -1.905 -1.82499 270)
			(size 0.6096 2.3622)
			(layers "F.Cu" "F.Mask" "F.Paste")
			(net "GND")
		)
		(pad "P5" smd rect
			(at -3.175 -1.82499 270)
			(size 0.6096 2.3622)
			(layers "F.Cu" "F.Mask" "F.Paste")
			(net "HDD_PRSNT_5")
		)
		(pad "P6" smd rect
			(at -4.445 -1.82499 270)
			(size 0.6096 2.3622)
			(layers "F.Cu" "F.Mask" "F.Paste")
			(net "GND")
		)
		(pad "P7" smd rect
			(at -5.715 -1.82499 270)
			(size 0.6096 2.3622)
			(layers "F.Cu" "F.Mask" "F.Paste")
			(net "5V_PRE_5")
		)
		(pad "P8" smd rect
			(at -6.985 -1.82499 270)
			(size 0.6096 2.3622)
			(layers "F.Cu" "F.Mask" "F.Paste")
			(net "P5V_HDD5")
		)
		(pad "P9" smd rect
			(at -8.255 -1.82499 270)
			(size 0.6096 2.3622)
			(layers "F.Cu" "F.Mask" "F.Paste")
			(net "P5V_HDD5")
		)
		(pad "P10" smd rect
			(at -9.525 -1.82499 270)
			(size 0.6096 2.3622)
			(layers "F.Cu" "F.Mask" "F.Paste")
			(net "GND")
		)
		(pad "P11" smd rect
			(at -10.795 -1.82499 270)
			(size 0.6096 2.3622)
			(layers "F.Cu" "F.Mask" "F.Paste")
			(net "ACT_HDD_5")
		)
		(pad "P12" smd rect
			(at -12.065 -1.82499 270)
			(size 0.6096 2.3622)
			(layers "F.Cu" "F.Mask" "F.Paste")
			(net "GND")
		)
		(pad "P13" smd rect
			(at -13.335 -1.82499 270)
			(size 0.6096 2.3622)
			(layers "F.Cu" "F.Mask" "F.Paste")
			(net "12V_PRE_5")
		)
		(pad "P14" smd rect
			(at -14.605 -1.82499 270)
			(size 0.6096 2.3622)
			(layers "F.Cu" "F.Mask" "F.Paste")
			(net "P12V_HDD5")
		)
		(pad "P15" smd rect
			(at -15.875 -1.82499 270)
			(size 0.6096 2.3622)
			(layers "F.Cu" "F.Mask" "F.Paste")
			(net "P12V_HDD5")
		)
		(pad "S1" smd rect
			(at 15.875 -1.82499 270)
			(size 0.6096 2.3622)
			(layers "F.Cu" "F.Mask" "F.Paste")
			(net "GND")
		)
		(pad "S2" smd rect
			(at 14.605 -1.82499 270)
			(size 0.6096 2.3622)
			(layers "F.Cu" "F.Mask" "F.Paste")
			(net "SAS_HDD_RX_P5")
		)
		(pad "S3" smd rect
			(at 13.335 -1.82499 270)
			(size 0.6096 2.3622)
			(layers "F.Cu" "F.Mask" "F.Paste")
			(net "SAS_HDD_RX_N5")
		)
		(pad "S4" smd rect
			(at 12.065 -1.82499 270)
			(size 0.6096 2.3622)
			(layers "F.Cu" "F.Mask" "F.Paste")
			(net "GND")
		)
		(pad "S5" smd rect
			(at 10.795 -1.82499 270)
			(size 0.6096 2.3622)
			(layers "F.Cu" "F.Mask" "F.Paste")
			(net "PHY_DRV_A_TO_SCC_A_5_DN")
		)
		(pad "S6" smd rect
			(at 9.525 -1.82499 270)
			(size 0.6096 2.3622)
			(layers "F.Cu" "F.Mask" "F.Paste")
			(net "PHY_DRV_A_TO_SCC_A_5_DP")
		)
		(pad "S7" smd rect
			(at 8.255 -1.82499 270)
			(size 0.6096 2.3622)
			(layers "F.Cu" "F.Mask" "F.Paste")
			(net "GND")
		)
		(pad "S8" smd rect
			(at 7.480046 2.845054 270)
			(size 0.508 2.3622)
			(layers "F.Cu" "F.Mask" "F.Paste")
			(net "GND")
		)
		(pad "S9" smd rect
			(at 6.679946 2.845054 270)
			(size 0.508 2.3622)
			(layers "F.Cu" "F.Mask" "F.Paste")
			(net "Net_477")
		)
		(pad "S10" smd rect
			(at 5.8801 2.845054 270)
			(size 0.508 2.3622)
			(layers "F.Cu" "F.Mask" "F.Paste")
			(net "Net_369")
		)
		(pad "S11" smd rect
			(at 5.08 2.845054 270)
			(size 0.508 2.3622)
			(layers "F.Cu" "F.Mask" "F.Paste")
			(net "GND")
		)
		(pad "S12" smd rect
			(at 4.2799 2.845054 270)
			(size 0.508 2.3622)
			(layers "F.Cu" "F.Mask" "F.Paste")
			(net "Net_405")
		)
		(pad "S13" smd rect
			(at 3.480054 2.845054 270)
			(size 0.508 2.3622)
			(layers "F.Cu" "F.Mask" "F.Paste")
			(net "Net_441")
		)
		(pad "S14" smd rect
			(at 2.679954 2.845054 270)
			(size 0.508 2.3622)
			(layers "F.Cu" "F.Mask" "F.Paste")
			(net "GND")
		)
		(zone
			(layer "F.Cu")
			(hatch none 0.5)
			(connect_pads
				(clearance 0)
			)
			(min_thickness 0.25)
			(keepout
				(tracks allowed)
				(vias not_allowed)
				(pads allowed)
				(copperpour not_allowed)
				(footprints allowed)
			)
			(placement
				(enabled no)
				(sheetname "")
			)
			(fill
				(thermal_gap 0.5)
				(thermal_bridge_width 0.5)
				(island_removal_mode 0)
			)
			(polygon
				(pts
					(xy 189.607698 -304.648616) (xy 182.533798 -304.648616) (xy 182.533798 -311.582816) (xy 183.638698 -311.582816)
					(xy 183.638698 -307.468016) (xy 188.261498 -307.468016) (xy 188.261498 -311.582816) (xy 189.607698 -311.582816)
				)
			)
		)
		(zone
			(layer "F.Cu")
			(hatch none 0.5)
			(connect_pads
				(clearance 0)
			)
			(min_thickness 0.25)
			(keepout
				(tracks not_allowed)
				(vias allowed)
				(pads allowed)
				(copperpour not_allowed)
				(footprints allowed)
			)
			(placement
				(enabled no)
				(sheetname "")
			)
			(fill
				(thermal_gap 0.5)
				(thermal_bridge_width 0.5)
				(island_removal_mode 0)
			)
			(polygon
				(pts
					(xy 189.607698 -304.648616) (xy 182.533798 -304.648616) (xy 182.533798 -311.582816) (xy 183.638698 -311.582816)
					(xy 183.638698 -307.468016) (xy 188.261498 -307.468016) (xy 188.261498 -311.582816) (xy 189.607698 -311.582816)
				)
			)
		)
		(zone
			(layer "F.Cu")
			(hatch none 0.5)
			(connect_pads
				(clearance 0)
			)
			(min_thickness 0.25)
			(keepout
				(tracks allowed)
				(vias not_allowed)
				(pads allowed)
				(copperpour not_allowed)
				(footprints allowed)
			)
			(placement
				(enabled no)
				(sheetname "")
			)
			(fill
				(thermal_gap 0.5)
				(thermal_bridge_width 0.5)
				(island_removal_mode 0)
			)
			(polygon
				(pts
					(xy 189.607698 -271.171416) (xy 182.533798 -271.171416) (xy 182.533798 -264.237216) (xy 183.638698 -264.237216)
					(xy 183.638698 -268.352016) (xy 188.261498 -268.352016) (xy 188.261498 -264.237216) (xy 189.607698 -264.237216)
				)
			)
		)
		(zone
			(layer "F.Cu")
			(hatch none 0.5)
			(connect_pads
				(clearance 0)
			)
			(min_thickness 0.25)
			(keepout
				(tracks not_allowed)
				(vias allowed)
				(pads allowed)
				(copperpour not_allowed)
				(footprints allowed)
			)
			(placement
				(enabled no)
				(sheetname "")
			)
			(fill
				(thermal_gap 0.5)
				(thermal_bridge_width 0.5)
				(island_removal_mode 0)
			)
			(polygon
				(pts
					(xy 189.607698 -271.171416) (xy 182.533798 -271.171416) (xy 182.533798 -264.237216) (xy 183.638698 -264.237216)
					(xy 183.638698 -268.352016) (xy 188.261498 -268.352016) (xy 188.261498 -264.237216) (xy 189.607698 -264.237216)
				)
			)
		)
		(zone
			(layers "F.Cu" "B.Cu" "In1.Cu" "In2.Cu" "In3.Cu" "In4.Cu" "In5.Cu" "In6.Cu"
				"In7.Cu" "In8.Cu" "In9.Cu" "In10.Cu"
			)
			(hatch none 0.5)
			(connect_pads
				(clearance 0)
			)
			(min_thickness 0.25)
			(keepout
				(tracks not_allowed)
				(vias allowed)
				(pads allowed)
				(copperpour not_allowed)
				(footprints allowed)
			)
			(placement
				(enabled no)
				(sheetname "")
			)
			(fill
				(thermal_gap 0.5)
				(thermal_bridge_width 0.5)
				(island_removal_mode 0)
			)
			(polygon
				(pts
					(arc
						(start 186.724798 -269.035022)
						(mid 185.175398 -269.035022)
						(end 186.724798 -269.035022)
					)
				)
			)
		)
		(zone
			(layers "F.Cu" "B.Cu" "In1.Cu" "In2.Cu" "In3.Cu" "In4.Cu" "In5.Cu" "In6.Cu"
				"In7.Cu" "In8.Cu" "In9.Cu" "In10.Cu"
			)
			(hatch none 0.5)
			(connect_pads
				(clearance 0)
			)
			(min_thickness 0.25)
			(keepout
				(tracks not_allowed)
				(vias allowed)
				(pads allowed)
				(copperpour not_allowed)
				(footprints allowed)
			)
			(placement
				(enabled no)
				(sheetname "")
			)
			(fill
				(thermal_gap 0.5)
				(thermal_bridge_width 0.5)
				(island_removal_mode 0)
			)
			(polygon
				(pts
					(arc
						(start 186.927998 -306.78501)
						(mid 184.972198 -306.78501)
						(end 186.927998 -306.78501)
					)
				)
			)
		)
	)
	(footprint ""
		(layer "F.Cu")
		(at 131.006596 -292.270942)
		(property "Reference" "R198"
			(at 0 0 0)
			(layer "F.SilkS")
			(hide yes)
			(effects
				(font
					(size 1.27 1.27)
				)
			)
		)
		(property "Value" "2R6F-GP"
			(at -0.0508 -4.8514 0)
			(unlocked yes)
			(layer "F.Fab")
			(hide yes)
			(effects
				(font
					(size 1.016 1.016)
					(thickness 0.1524)
				)
			)
		)
		(property "Device Type" "R1206H26"
			(at 0 -6.3754 0)
			(unlocked yes)
			(layer "F.Fab")
			(hide yes)
			(effects
				(font
					(size 1.016 1.016)
					(thickness 0.1524)
				)
			)
		)
		(duplicate_pad_numbers_are_jumpers no)
		(fp_line
			(start -1.016 -2.2352)
			(end 1.016 -2.2352)
			(stroke
				(width 0.1524)
				(type default)
			)
			(layer "F.SilkS")
		)
		(fp_line
			(start -1.016 2.2352)
			(end -1.016 -2.2352)
			(stroke
				(width 0.1524)
				(type default)
			)
			(layer "F.SilkS")
		)
		(fp_line
			(start 1.016 -2.2352)
			(end 1.016 2.2352)
			(stroke
				(width 0.1524)
				(type default)
			)
			(layer "F.SilkS")
		)
		(fp_line
			(start 1.016 2.2352)
			(end -1.016 2.2352)
			(stroke
				(width 0.1524)
				(type default)
			)
			(layer "F.SilkS")
		)
		(fp_rect
			(start -1.0922 2.3114)
			(end 1.0922 -2.3114)
			(stroke
				(width 0)
				(type default)
			)
			(fill no)
			(layer "F.CrtYd")
		)
		(fp_poly
			(pts
				(xy -1.0922 -2.3114) (xy 1.0922 -2.3114) (xy 1.0922 2.3114) (xy -1.0922 2.3114)
			)
			(stroke
				(width 0)
				(type default)
			)
			(fill no)
			(layer "F.Fab")
		)
		(pad "1" smd rect
			(at 0 -1.397)
			(size 1.651 1.27)
			(layers "F.Cu" "F.Mask" "F.Paste")
			(net "P5V_HDD3")
		)
		(pad "2" smd rect
			(at 0 1.397)
			(size 1.651 1.27)
			(layers "F.Cu" "F.Mask" "F.Paste")
			(net "5V_PRE_3")
		)
	)
	(footprint ""
		(layer "F.Cu")
		(at 28.575 -253.30912 180)
		(property "Reference" "R1223"
			(at 0 0 180)
			(layer "F.SilkS")
			(hide yes)
			(effects
				(font
					(size 1.27 1.27)
				)
			)
		)
		(property "Value" "0R2J-2-GP"
			(at 0.064008 -3.993896 180)
			(unlocked yes)
			(layer "F.Fab")
			(hide yes)
			(effects
				(font
					(size 1.016 1.016)
					(thickness 0.1524)
				)
			)
		)
		(property "Device Type" "R402H16"
			(at 0.064008 -5.517896 180)
			(unlocked yes)
			(layer "F.Fab")
			(hide yes)
			(effects
				(font
					(size 1.016 1.016)
					(thickness 0.1524)
				)
			)
		)
		(duplicate_pad_numbers_are_jumpers no)
		(fp_line
			(start 0.508 -0.9398)
			(end -0.508 -0.9398)
			(stroke
				(width 0.1524)
				(type default)
			)
			(layer "F.SilkS")
		)
		(fp_line
			(start -0.508 -0.9398)
			(end -0.508 0.9398)
			(stroke
				(width 0.1524)
				(type default)
			)
			(layer "F.SilkS")
		)
		(fp_rect
			(start -0.508 0.9398)
			(end 0.508 -0.9398)
			(stroke
				(width 0)
				(type default)
			)
			(fill no)
			(layer "F.CrtYd")
		)
		(fp_rect
			(start -0.508 0.9398)
			(end 0.508 -0.9398)
			(stroke
				(width 0)
				(type default)
			)
			(fill no)
			(layer "F.Fab")
		)
		(pad "1" smd custom
			(at 0 -0.4445 180)
			(size 0.1397 0.1397)
			(layers "F.Cu" "F.Mask" "F.Paste")
			(net "P5V_A_ROVP")
			(options
				(clearance outline)
				(anchor circle)
			)
			(primitives
				(gr_poly
					(pts
						(arc
							(start -0.1778 -0.2794)
							(mid -0.249642 -0.249642)
							(end -0.2794 -0.1778)
						)
						(arc
							(start -0.2794 0.1778)
							(mid -0.249642 0.249642)
							(end -0.1778 0.2794)
						)
						(arc
							(start 0.1778 0.2794)
							(mid 0.249642 0.249642)
							(end 0.2794 0.1778)
						)
						(arc
							(start 0.2794 -0.1778)
							(mid 0.249642 -0.249642)
							(end 0.1778 -0.2794)
						)
					)
					(width 0)
					(fill yes)
				)
			)
		)
		(pad "2" smd custom
			(at 0 0.4445 180)
			(size 0.1397 0.1397)
			(layers "F.Cu" "F.Mask" "F.Paste")
			(net "AGND_P5V_A")
			(options
				(clearance outline)
				(anchor circle)
			)
			(primitives
				(gr_poly
					(pts
						(arc
							(start -0.1778 -0.2794)
							(mid -0.249642 -0.249642)
							(end -0.2794 -0.1778)
						)
						(arc
							(start -0.2794 0.1778)
							(mid -0.249642 0.249642)
							(end -0.1778 0.2794)
						)
						(arc
							(start 0.1778 0.2794)
							(mid 0.249642 0.249642)
							(end 0.2794 0.1778)
						)
						(arc
							(start 0.2794 -0.1778)
							(mid 0.249642 -0.249642)
							(end 0.1778 -0.2794)
						)
					)
					(width 0)
					(fill yes)
				)
			)
		)
	)
	(footprint ""
		(layer "F.Cu")
		(at 49.466246 -158.982918 180)
		(property "Reference" "D13"
			(at 0 0 180)
			(layer "F.SilkS")
			(hide yes)
			(effects
				(font
					(size 1.27 1.27)
				)
			)
		)
		(property "Value" "RB551V30-GP"
			(at 0 -6.7818 180)
			(unlocked yes)
			(layer "F.Fab")
			(hide yes)
			(effects
				(font
					(size 1.016 1.016)
					(thickness 0.1524)
				)
			)
		)
		(property "Device Type" "SOD323AKH38"
			(at 0 -8.6868 180)
			(unlocked yes)
			(layer "F.Fab")
			(hide yes)
			(effects
				(font
					(size 1.016 1.016)
					(thickness 0.1524)
				)
			)
		)
		(duplicate_pad_numbers_are_jumpers no)
		(fp_line
			(start 0.889 2.159)
			(end -0.889 2.159)
			(stroke
				(width 0.1524)
				(type default)
			)
			(layer "F.SilkS")
		)
		(fp_line
			(start 0.889 -1.9304)
			(end 0.889 2.159)
			(stroke
				(width 0.1524)
				(type default)
			)
			(layer "F.SilkS")
		)
		(fp_line
			(start 0.762 2.0574)
			(end -0.762 2.0574)
			(stroke
				(width 0.508)
				(type default)
			)
			(layer "F.SilkS")
		)
		(fp_line
			(start -0.889 2.159)
			(end -0.889 -1.9304)
			(stroke
				(width 0.1524)
				(type default)
			)
			(layer "F.SilkS")
		)
		(fp_line
			(start -0.889 -1.9304)
			(end 0.889 -1.9304)
			(stroke
				(width 0.1524)
				(type default)
			)
			(layer "F.SilkS")
		)
		(fp_rect
			(start -1.016 2.3114)
			(end 1.016 -2.0066)
			(stroke
				(width 0)
				(type default)
			)
			(fill no)
			(layer "F.CrtYd")
		)
		(fp_poly
			(pts
				(xy -1.016 -2.0066) (xy 1.016 -2.0066) (xy 1.016 2.3114) (xy -1.016 2.3114)
			)
			(stroke
				(width 0)
				(type default)
			)
			(fill no)
			(layer "F.Fab")
		)
		(pad "A" smd rect
			(at 0 -1.143 180)
			(size 0.5588 1.016)
			(layers "F.Cu" "F.Mask" "F.Paste")
			(net "SW_HDD_R13")
		)
		(pad "K" smd rect
			(at 0 1.143 180)
			(size 0.5588 1.016)
			(layers "F.Cu" "F.Mask" "F.Paste")
			(net "SW_HDD_N13")
		)
	)
)
